(kicad_pcb
	(version 20260206)
	(generator "pcbnew")
	(generator_version "10.0")
	(general
		(thickness 1.6)
		(legacy_teardrops no)
	)
	(paper "A4")
	(title_block
		(title "01162023_DA0F0TEBIF0_F0T_Expander_BD_F_brd_V02_OCP.brd")
		(comment 1 "Grand Teton / footprints 3884-3890 of 9728")
	)
	(layers
		(0 "F.Cu" signal "TOP")
		(4 "In1.Cu" signal "GND")
		(6 "In2.Cu" signal "VCC")
		(8 "In3.Cu" signal "VCC1")
		(10 "In4.Cu" signal "GND1")
		(12 "In5.Cu" signal "IN1")
		(14 "In6.Cu" signal "GND2")
		(16 "In7.Cu" signal "IN2")
		(18 "In8.Cu" signal "GND3")
		(20 "In9.Cu" signal "IN3")
		(22 "In10.Cu" signal "GND4")
		(24 "In11.Cu" signal "IN4")
		(26 "In12.Cu" signal "GND5")
		(28 "In13.Cu" signal "IN5")
		(30 "In14.Cu" signal "GND6")
		(32 "In15.Cu" signal "IN6")
		(34 "In16.Cu" signal "GND7")
		(2 "B.Cu" signal "BOTTOM")
		(9 "F.Adhes" user "F.Adhesive")
		(11 "B.Adhes" user "B.Adhesive")
		(13 "F.Paste" user "Package Geometry/Pastemask Top")
		(15 "B.Paste" user "Package Geometry/Pastemask Bottom")
		(5 "F.SilkS" user "Ref Des/Silkscreen Top")
		(7 "B.SilkS" user "Ref Des/Silkscreen Bottom")
		(1 "F.Mask" user "Board Geometry/Soldermask Top")
		(3 "B.Mask" user "Board Geometry/Soldermask Bottom")
		(17 "Dwgs.User" user "User.Drawings")
		(19 "Cmts.User" user "User.Comments")
		(21 "Eco1.User" user "User.Eco1")
		(23 "Eco2.User" user "User.Eco2")
		(25 "Edge.Cuts" user "Board Geometry/Outline")
		(27 "Margin" user)
		(31 "F.CrtYd" user "Package Geometry/Place Bound Top")
		(29 "B.CrtYd" user "Package Geometry/Place Bound Bottom")
		(35 "F.Fab" user "Ref Des/Assembly Top")
		(33 "B.Fab" user "Ref Des/Assembly Bottom")
	)
	(footprint ""
		(layer "F.Cu")
		(at 230.18877 -258.389374 -90)
		(property "Reference" "R6495"
			(at 0 0 270)
			(layer "F.SilkS")
			(hide yes)
			(effects
				(font
					(size 1.27 1.27)
				)
			)
		)
		(property "Value" ""
			(at 0 0 270)
			(layer "F.Fab")
			(effects
				(font
					(size 1.27 1.27)
				)
			)
		)
		(duplicate_pad_numbers_are_jumpers no)
		(fp_line
			(start -0.7874 0.4064)
			(end -0.7874 -0.4064)
			(stroke
				(width 0.1524)
				(type default)
			)
			(layer "F.SilkS")
		)
		(fp_line
			(start 0.7874 0.4064)
			(end -0.7874 0.4064)
			(stroke
				(width 0.1524)
				(type default)
			)
			(layer "F.SilkS")
		)
		(fp_line
			(start -0.7874 -0.4064)
			(end 0.7874 -0.4064)
			(stroke
				(width 0.1524)
				(type default)
			)
			(layer "F.SilkS")
		)
		(fp_line
			(start 0.7874 -0.4064)
			(end 0.7874 0.4064)
			(stroke
				(width 0.1524)
				(type default)
			)
			(layer "F.SilkS")
		)
		(fp_line
			(start -0.67945 0.3048)
			(end -0.67945 -0.305054)
			(stroke
				(width 0.1)
				(type default)
			)
			(layer "F.Fab")
		)
		(fp_line
			(start -0.12065 0.3048)
			(end -0.67945 0.3048)
			(stroke
				(width 0.1)
				(type default)
			)
			(layer "F.Fab")
		)
		(fp_line
			(start 0.120396 0.3048)
			(end 0.120396 0.2794)
			(stroke
				(width 0.1)
				(type default)
			)
			(layer "F.Fab")
		)
		(fp_line
			(start 0.67945 0.3048)
			(end 0.120396 0.3048)
			(stroke
				(width 0.1)
				(type default)
			)
			(layer "F.Fab")
		)
		(fp_line
			(start -0.12065 0.2794)
			(end -0.12065 0.3048)
			(stroke
				(width 0.1)
				(type default)
			)
			(layer "F.Fab")
		)
		(fp_line
			(start 0.120396 0.2794)
			(end -0.12065 0.2794)
			(stroke
				(width 0.1)
				(type default)
			)
			(layer "F.Fab")
		)
		(fp_line
			(start -0.12065 -0.2794)
			(end 0.12065 -0.2794)
			(stroke
				(width 0.1)
				(type default)
			)
			(layer "F.Fab")
		)
		(fp_line
			(start 0.12065 -0.2794)
			(end 0.12065 -0.3048)
			(stroke
				(width 0.1)
				(type default)
			)
			(layer "F.Fab")
		)
		(fp_line
			(start 0.12065 -0.3048)
			(end 0.67945 -0.3048)
			(stroke
				(width 0.1)
				(type default)
			)
			(layer "F.Fab")
		)
		(fp_line
			(start 0.67945 -0.3048)
			(end 0.67945 0.3048)
			(stroke
				(width 0.1)
				(type default)
			)
			(layer "F.Fab")
		)
		(fp_line
			(start -0.67945 -0.305054)
			(end -0.12065 -0.305054)
			(stroke
				(width 0.1)
				(type default)
			)
			(layer "F.Fab")
		)
		(fp_line
			(start -0.12065 -0.305054)
			(end -0.12065 -0.2794)
			(stroke
				(width 0.1)
				(type default)
			)
			(layer "F.Fab")
		)
		(pad "1" smd circle
			(at -0.40005 0 270)
			(size 0 0)
			(layers "F.Cu" "F.Mask" "F.Paste")
			(net "P1V25_SERDES_VDDPLL_PEX1")
		)
		(pad "2" smd circle
			(at 0.40005 0 270)
			(size 0 0)
			(layers "F.Cu" "F.Mask" "F.Paste")
			(net "P1V25_SERDES_VDDPLL_PEX1_C4")
		)
	)
	(footprint ""
		(layer "F.Cu")
		(at 228.695504 -155.940506 -90)
		(property "Reference" "R1205"
			(at 0 0 270)
			(layer "F.SilkS")
			(hide yes)
			(effects
				(font
					(size 1.27 1.27)
				)
			)
		)
		(property "Value" ""
			(at 0 0 270)
			(layer "F.Fab")
			(effects
				(font
					(size 1.27 1.27)
				)
			)
		)
		(duplicate_pad_numbers_are_jumpers no)
		(fp_line
			(start 0.7874 0.4064)
			(end -0.7874 0.4064)
			(stroke
				(width 0.1524)
				(type default)
			)
			(layer "F.SilkS")
		)
		(fp_line
			(start -0.67945 0.3048)
			(end -0.67945 -0.305054)
			(stroke
				(width 0.1)
				(type default)
			)
			(layer "F.Fab")
		)
		(fp_line
			(start -0.12065 0.3048)
			(end -0.67945 0.3048)
			(stroke
				(width 0.1)
				(type default)
			)
			(layer "F.Fab")
		)
		(fp_line
			(start 0.120396 0.3048)
			(end 0.120396 0.2794)
			(stroke
				(width 0.1)
				(type default)
			)
			(layer "F.Fab")
		)
		(fp_line
			(start 0.67945 0.3048)
			(end 0.120396 0.3048)
			(stroke
				(width 0.1)
				(type default)
			)
			(layer "F.Fab")
		)
		(fp_line
			(start -0.12065 0.2794)
			(end -0.12065 0.3048)
			(stroke
				(width 0.1)
				(type default)
			)
			(layer "F.Fab")
		)
		(fp_line
			(start 0.120396 0.2794)
			(end -0.12065 0.2794)
			(stroke
				(width 0.1)
				(type default)
			)
			(layer "F.Fab")
		)
		(fp_line
			(start -0.12065 -0.2794)
			(end 0.12065 -0.2794)
			(stroke
				(width 0.1)
				(type default)
			)
			(layer "F.Fab")
		)
		(fp_line
			(start 0.12065 -0.2794)
			(end 0.12065 -0.3048)
			(stroke
				(width 0.1)
				(type default)
			)
			(layer "F.Fab")
		)
		(fp_line
			(start 0.12065 -0.3048)
			(end 0.67945 -0.3048)
			(stroke
				(width 0.1)
				(type default)
			)
			(layer "F.Fab")
		)
		(fp_line
			(start 0.67945 -0.3048)
			(end 0.67945 0.3048)
			(stroke
				(width 0.1)
				(type default)
			)
			(layer "F.Fab")
		)
		(fp_line
			(start -0.67945 -0.305054)
			(end -0.12065 -0.305054)
			(stroke
				(width 0.1)
				(type default)
			)
			(layer "F.Fab")
		)
		(fp_line
			(start -0.12065 -0.305054)
			(end -0.12065 -0.2794)
			(stroke
				(width 0.1)
				(type default)
			)
			(layer "F.Fab")
		)
		(pad "1" smd circle
			(at -0.40005 0 270)
			(size 0 0)
			(layers "F.Cu" "F.Mask" "F.Paste")
			(net "CLK_100M_PEX0_REF_R_DP")
		)
		(pad "2" smd circle
			(at 0.40005 0 270)
			(size 0 0)
			(layers "F.Cu" "F.Mask" "F.Paste")
			(net "CLK_100M_PEX0_REF_DP")
		)
	)
	(footprint ""
		(layer "F.Cu")
		(at 363.474 -203.835)
		(property "Reference" "R4673"
			(at 0 0 0)
			(layer "F.SilkS")
			(hide yes)
			(effects
				(font
					(size 1.27 1.27)
				)
			)
		)
		(property "Value" ""
			(at 0 0 0)
			(layer "F.Fab")
			(effects
				(font
					(size 1.27 1.27)
				)
			)
		)
		(duplicate_pad_numbers_are_jumpers no)
		(fp_line
			(start -0.7874 -0.4064)
			(end 0.7874 -0.4064)
			(stroke
				(width 0.1524)
				(type default)
			)
			(layer "F.SilkS")
		)
		(fp_line
			(start -0.7874 0.4064)
			(end -0.7874 -0.4064)
			(stroke
				(width 0.1524)
				(type default)
			)
			(layer "F.SilkS")
		)
		(fp_line
			(start 0.7874 -0.4064)
			(end 0.7874 0.4064)
			(stroke
				(width 0.1524)
				(type default)
			)
			(layer "F.SilkS")
		)
		(fp_line
			(start 0.7874 0.4064)
			(end -0.7874 0.4064)
			(stroke
				(width 0.1524)
				(type default)
			)
			(layer "F.SilkS")
		)
		(fp_line
			(start -0.67945 -0.305054)
			(end -0.12065 -0.305054)
			(stroke
				(width 0.1)
				(type default)
			)
			(layer "F.Fab")
		)
		(fp_line
			(start -0.67945 0.3048)
			(end -0.67945 -0.305054)
			(stroke
				(width 0.1)
				(type default)
			)
			(layer "F.Fab")
		)
		(fp_line
			(start -0.12065 -0.305054)
			(end -0.12065 -0.2794)
			(stroke
				(width 0.1)
				(type default)
			)
			(layer "F.Fab")
		)
		(fp_line
			(start -0.12065 -0.2794)
			(end 0.12065 -0.2794)
			(stroke
				(width 0.1)
				(type default)
			)
			(layer "F.Fab")
		)
		(fp_line
			(start -0.12065 0.2794)
			(end -0.12065 0.3048)
			(stroke
				(width 0.1)
				(type default)
			)
			(layer "F.Fab")
		)
		(fp_line
			(start -0.12065 0.3048)
			(end -0.67945 0.3048)
			(stroke
				(width 0.1)
				(type default)
			)
			(layer "F.Fab")
		)
		(fp_line
			(start 0.120396 0.2794)
			(end -0.12065 0.2794)
			(stroke
				(width 0.1)
				(type default)
			)
			(layer "F.Fab")
		)
		(fp_line
			(start 0.120396 0.3048)
			(end 0.120396 0.2794)
			(stroke
				(width 0.1)
				(type default)
			)
			(layer "F.Fab")
		)
		(fp_line
			(start 0.12065 -0.3048)
			(end 0.67945 -0.3048)
			(stroke
				(width 0.1)
				(type default)
			)
			(layer "F.Fab")
		)
		(fp_line
			(start 0.12065 -0.2794)
			(end 0.12065 -0.3048)
			(stroke
				(width 0.1)
				(type default)
			)
			(layer "F.Fab")
		)
		(fp_line
			(start 0.67945 -0.3048)
			(end 0.67945 0.3048)
			(stroke
				(width 0.1)
				(type default)
			)
			(layer "F.Fab")
		)
		(fp_line
			(start 0.67945 0.3048)
			(end 0.120396 0.3048)
			(stroke
				(width 0.1)
				(type default)
			)
			(layer "F.Fab")
		)
		(pad "1" smd circle
			(at -0.40005 0)
			(size 0 0)
			(layers "F.Cu" "F.Mask" "F.Paste")
			(net "PEX1_PCA9555_INT_N")
		)
		(pad "2" smd circle
			(at 0.40005 0)
			(size 0 0)
			(layers "F.Cu" "F.Mask" "F.Paste")
			(net "PEX1_PCA9555_0_INT_N")
		)
	)
	(footprint ""
		(layer "F.Cu")
		(at 248.93143 -92.096336 90)
		(property "Reference" "R1058"
			(at 0 0 90)
			(layer "F.SilkS")
			(hide yes)
			(effects
				(font
					(size 1.27 1.27)
				)
			)
		)
		(property "Value" ""
			(at 0 0 90)
			(layer "F.Fab")
			(effects
				(font
					(size 1.27 1.27)
				)
			)
		)
		(duplicate_pad_numbers_are_jumpers no)
		(fp_line
			(start 0.7874 -0.4064)
			(end 0.7874 0.4064)
			(stroke
				(width 0.1524)
				(type default)
			)
			(layer "F.SilkS")
		)
		(fp_line
			(start -0.7874 -0.4064)
			(end 0.7874 -0.4064)
			(stroke
				(width 0.1524)
				(type default)
			)
			(layer "F.SilkS")
		)
		(fp_line
			(start 0.7874 0.4064)
			(end -0.7874 0.4064)
			(stroke
				(width 0.1524)
				(type default)
			)
			(layer "F.SilkS")
		)
		(fp_line
			(start -0.7874 0.4064)
			(end -0.7874 -0.4064)
			(stroke
				(width 0.1524)
				(type default)
			)
			(layer "F.SilkS")
		)
		(fp_line
			(start -0.12065 -0.305054)
			(end -0.12065 -0.2794)
			(stroke
				(width 0.1)
				(type default)
			)
			(layer "F.Fab")
		)
		(fp_line
			(start -0.67945 -0.305054)
			(end -0.12065 -0.305054)
			(stroke
				(width 0.1)
				(type default)
			)
			(layer "F.Fab")
		)
		(fp_line
			(start 0.67945 -0.3048)
			(end 0.67945 0.3048)
			(stroke
				(width 0.1)
				(type default)
			)
			(layer "F.Fab")
		)
		(fp_line
			(start 0.12065 -0.3048)
			(end 0.67945 -0.3048)
			(stroke
				(width 0.1)
				(type default)
			)
			(layer "F.Fab")
		)
		(fp_line
			(start 0.12065 -0.2794)
			(end 0.12065 -0.3048)
			(stroke
				(width 0.1)
				(type default)
			)
			(layer "F.Fab")
		)
		(fp_line
			(start -0.12065 -0.2794)
			(end 0.12065 -0.2794)
			(stroke
				(width 0.1)
				(type default)
			)
			(layer "F.Fab")
		)
		(fp_line
			(start 0.120396 0.2794)
			(end -0.12065 0.2794)
			(stroke
				(width 0.1)
				(type default)
			)
			(layer "F.Fab")
		)
		(fp_line
			(start -0.12065 0.2794)
			(end -0.12065 0.3048)
			(stroke
				(width 0.1)
				(type default)
			)
			(layer "F.Fab")
		)
		(fp_line
			(start 0.67945 0.3048)
			(end 0.120396 0.3048)
			(stroke
				(width 0.1)
				(type default)
			)
			(layer "F.Fab")
		)
		(fp_line
			(start 0.120396 0.3048)
			(end 0.120396 0.2794)
			(stroke
				(width 0.1)
				(type default)
			)
			(layer "F.Fab")
		)
		(fp_line
			(start -0.12065 0.3048)
			(end -0.67945 0.3048)
			(stroke
				(width 0.1)
				(type default)
			)
			(layer "F.Fab")
		)
		(fp_line
			(start -0.67945 0.3048)
			(end -0.67945 -0.305054)
			(stroke
				(width 0.1)
				(type default)
			)
			(layer "F.Fab")
		)
		(pad "1" smd circle
			(at -0.40005 0 90)
			(size 0 0)
			(layers "F.Cu" "F.Mask" "F.Paste")
			(net "FM_CK440Q_DEV_25M_EN")
		)
		(pad "2" smd circle
			(at 0.40005 0 90)
			(size 0 0)
			(layers "F.Cu" "F.Mask" "F.Paste")
			(net "P3V3")
		)
	)
	(footprint ""
		(layer "F.Cu")
		(at 344.481404 -356.244906 90)
		(property "Reference" "C582"
			(at 0 0 90)
			(layer "F.SilkS")
			(hide yes)
			(effects
				(font
					(size 1.27 1.27)
				)
			)
		)
		(property "Value" ""
			(at 0 0 90)
			(layer "F.Fab")
			(effects
				(font
					(size 1.27 1.27)
				)
			)
		)
		(duplicate_pad_numbers_are_jumpers no)
		(fp_line
			(start 0.299974 -0.150114)
			(end 0.299974 0.150114)
			(stroke
				(width 0.1)
				(type default)
			)
			(layer "F.Fab")
		)
		(fp_line
			(start -0.299974 -0.150114)
			(end 0.299974 -0.150114)
			(stroke
				(width 0.1)
				(type default)
			)
			(layer "F.Fab")
		)
		(fp_line
			(start 0.299974 0.150114)
			(end -0.299974 0.150114)
			(stroke
				(width 0.1)
				(type default)
			)
			(layer "F.Fab")
		)
		(fp_line
			(start -0.299974 0.150114)
			(end -0.299974 -0.150114)
			(stroke
				(width 0.1)
				(type default)
			)
			(layer "F.Fab")
		)
		(pad "1" smd rect
			(at -0.2667 0 90)
			(size 0.3048 0.381)
			(layers "F.Cu" "F.Mask" "F.Paste")
			(net "P5E_PEX2_STN6_TX_DN<96>")
		)
		(pad "2" smd rect
			(at 0.2667 0 90)
			(size 0.3048 0.381)
			(layers "F.Cu" "F.Mask" "F.Paste")
			(net "P5E_PEX2_STN6_TX_C_DN<96>")
		)
	)
	(footprint ""
		(layer "F.Cu")
		(at 264.611358 -290.044632 -90)
		(property "Reference" "R4582"
			(at 0 0 270)
			(layer "F.SilkS")
			(hide yes)
			(effects
				(font
					(size 1.27 1.27)
				)
			)
		)
		(property "Value" ""
			(at 0 0 270)
			(layer "F.Fab")
			(effects
				(font
					(size 1.27 1.27)
				)
			)
		)
		(duplicate_pad_numbers_are_jumpers no)
		(fp_line
			(start -0.7874 0.4064)
			(end -0.7874 -0.4064)
			(stroke
				(width 0.1524)
				(type default)
			)
			(layer "F.SilkS")
		)
		(fp_line
			(start 0.7874 0.4064)
			(end -0.7874 0.4064)
			(stroke
				(width 0.1524)
				(type default)
			)
			(layer "F.SilkS")
		)
		(fp_line
			(start -0.7874 -0.4064)
			(end 0.7874 -0.4064)
			(stroke
				(width 0.1524)
				(type default)
			)
			(layer "F.SilkS")
		)
		(fp_line
			(start 0.7874 -0.4064)
			(end 0.7874 0.4064)
			(stroke
				(width 0.1524)
				(type default)
			)
			(layer "F.SilkS")
		)
		(fp_line
			(start -0.67945 0.3048)
			(end -0.67945 -0.305054)
			(stroke
				(width 0.1)
				(type default)
			)
			(layer "F.Fab")
		)
		(fp_line
			(start -0.12065 0.3048)
			(end -0.67945 0.3048)
			(stroke
				(width 0.1)
				(type default)
			)
			(layer "F.Fab")
		)
		(fp_line
			(start 0.120396 0.3048)
			(end 0.120396 0.2794)
			(stroke
				(width 0.1)
				(type default)
			)
			(layer "F.Fab")
		)
		(fp_line
			(start 0.67945 0.3048)
			(end 0.120396 0.3048)
			(stroke
				(width 0.1)
				(type default)
			)
			(layer "F.Fab")
		)
		(fp_line
			(start -0.12065 0.2794)
			(end -0.12065 0.3048)
			(stroke
				(width 0.1)
				(type default)
			)
			(layer "F.Fab")
		)
		(fp_line
			(start 0.120396 0.2794)
			(end -0.12065 0.2794)
			(stroke
				(width 0.1)
				(type default)
			)
			(layer "F.Fab")
		)
		(fp_line
			(start -0.12065 -0.2794)
			(end 0.12065 -0.2794)
			(stroke
				(width 0.1)
				(type default)
			)
			(layer "F.Fab")
		)
		(fp_line
			(start 0.12065 -0.2794)
			(end 0.12065 -0.3048)
			(stroke
				(width 0.1)
				(type default)
			)
			(layer "F.Fab")
		)
		(fp_line
			(start 0.12065 -0.3048)
			(end 0.67945 -0.3048)
			(stroke
				(width 0.1)
				(type default)
			)
			(layer "F.Fab")
		)
		(fp_line
			(start 0.67945 -0.3048)
			(end 0.67945 0.3048)
			(stroke
				(width 0.1)
				(type default)
			)
			(layer "F.Fab")
		)
		(fp_line
			(start -0.67945 -0.305054)
			(end -0.12065 -0.305054)
			(stroke
				(width 0.1)
				(type default)
			)
			(layer "F.Fab")
		)
		(fp_line
			(start -0.12065 -0.305054)
			(end -0.12065 -0.2794)
			(stroke
				(width 0.1)
				(type default)
			)
			(layer "F.Fab")
		)
		(pad "1" smd circle
			(at -0.40005 0 270)
			(size 0 0)
			(layers "F.Cu" "F.Mask" "F.Paste")
			(net "PCEPLL4_VDDA18_PEX2")
		)
		(pad "2" smd circle
			(at 0.40005 0 270)
			(size 0 0)
			(layers "F.Cu" "F.Mask" "F.Paste")
			(net "PCEPLL4_VDDA18_PEX2_R")
		)
	)
	(footprint ""
		(layer "F.Cu")
		(at 335.811368 -71.458074 -90)
		(property "Reference" "PD108"
			(at 4.148074 -2.822702 90)
			(unlocked yes)
			(layer "F.SilkS")
			(effects
				(font
					(size 0.7874 0.5842)
					(thickness 0.1524)
				)
				(justify left)
			)
		)
		(property "Value" ""
			(at 0 0 270)
			(layer "F.Fab")
			(effects
				(font
					(size 1.27 1.27)
				)
			)
		)
		(duplicate_pad_numbers_are_jumpers no)
		(fp_line
			(start -3.656584 1.970024)
			(end 4.240784 1.970024)
			(stroke
				(width 0.1524)
				(type default)
			)
			(layer "F.SilkS")
		)
		(fp_line
			(start 4.240784 1.970024)
			(end 4.240784 -1.970024)
			(stroke
				(width 0.1524)
				(type default)
			)
			(layer "F.SilkS")
		)
		(fp_line
			(start -3.656584 -1.970024)
			(end -3.656584 1.970024)
			(stroke
				(width 0.1524)
				(type default)
			)
			(layer "F.SilkS")
		)
		(fp_line
			(start 4.240784 -1.970024)
			(end -3.656584 -1.970024)
			(stroke
				(width 0.1524)
				(type default)
			)
			(layer "F.SilkS")
		)
		(fp_poly
			(pts
				(xy 3.580384 1.970024) (xy 3.580384 -1.970024) (xy 4.240784 -1.970024) (xy 4.240784 1.970024)
			)
			(stroke
				(width 0)
				(type default)
			)
			(fill yes)
			(layer "F.SilkS")
		)
		(fp_line
			(start -2.3749 1.970024)
			(end 2.3749 1.970024)
			(stroke
				(width 0.1)
				(type default)
			)
			(layer "F.Fab")
		)
		(fp_line
			(start 2.3749 1.970024)
			(end 2.3749 -1.970024)
			(stroke
				(width 0.1)
				(type default)
			)
			(layer "F.Fab")
		)
		(fp_line
			(start -2.3749 -1.970024)
			(end -2.3749 1.970024)
			(stroke
				(width 0.1)
				(type default)
			)
			(layer "F.Fab")
		)
		(fp_line
			(start 2.3749 -1.970024)
			(end -2.3749 -1.970024)
			(stroke
				(width 0.1)
				(type default)
			)
			(layer "F.Fab")
		)
		(fp_text user "+"
			(at -4.9784 -0.23495 270)
			(unlocked yes)
			(layer "F.Fab")
			(effects
				(font
					(size 1.905 1.4224)
					(thickness 0.1524)
				)
				(justify left)
			)
		)
		(fp_text user "-"
			(at 4.1656 -0.23495 270)
			(unlocked yes)
			(layer "F.Fab")
			(effects
				(font
					(size 1.905 1.4224)
					(thickness 0.1524)
				)
				(justify left)
			)
		)
		(pad "A" smd rect
			(at -2.450084 0 270)
			(size 2.159 2.2606)
			(layers "F.Cu" "F.Mask" "F.Paste")
			(net "GND")
		)
		(pad "C" smd rect
			(at 2.450084 0 270)
			(size 2.159 2.2606)
			(layers "F.Cu" "F.Mask" "F.Paste")
			(net "P12V_AUX")
		)
	)
)
